FILE_TYPE = CONNECTIVITY;
{Allegro Design Entry HDL 17.2-2016 S081 (4005846) 1/11/2022}
"PAGE_NUMBER" = 72;
0"NC";
1"GND\g";
2"PVDDCR_CPU0_P1\g";
3"GND\g";
4"PVDDCR_CPU0_P1\g";
5"PVDDCR_CPU0_P1\g";
6"GND\g";
7"PVDDCR_CPU0_P1\g";
8"GND\g";
9"PVDDCR_CPU0_P1\g";
10"GND\g";
11"GND\g";
12"PVDDCR_CPU1_P1\g";
13"GND\g";
14"GND\g";
15"PVDDCR_CPU1_P1\g";
16"PVDDCR_CPU1_P1\g";
17"GND\g";
18"PVDDCR_CPU1_P1\g";
19"PVDDCR_CPU1_P1\g";
20"GND\g";
%"Q_CAP"
"1","(-9400,1325)","0","pure_quanta","I1";
;
LOCATION"C2298"
$SEC"1"
CDS_SEC"1"
MATERIAL"X6S"
TOLERANCE"20%"
VALUE"22UF"
PART_NUMBER"CH622KMEB02"
VOLTAGE"4V"
PACK_TYPE"C0402"
CDS_LIB"pure_quanta";
"B"
$PN"2"3;
"A"
$PN"1"2;
%"Q_CAP"
"1","(-8950,2125)","0","pure_quanta","I10";
;
LOCATION"C2303"
$SEC"1"
CDS_SEC"1"
MATERIAL"X6S"
TOLERANCE"20%"
VALUE"22UF"
PART_NUMBER"CH622KMEB02"
VOLTAGE"4V"
PACK_TYPE"C0402"
CDS_LIB"pure_quanta";
"B"
$PN"2"1;
"A"
$PN"1"4;
%"Q_CAP"
"1","(-825,3725)","0","pure_quanta","I100";
;
LOCATION"C2403"
$SEC"1"
CDS_SEC"1"
MATERIAL"X6S"
TOLERANCE"20%"
VALUE"22UF"
PART_NUMBER"CH622KMEB02"
VOLTAGE"4V"
PACK_TYPE"C0402"
CDS_LIB"pure_quanta";
"B"
$PN"2"17;
"A"
$PN"1"16;
%"Q_CAP"
"1","(-3925,4500)","0","pure_quanta","I101";
;
LOCATION"C2362"
$SEC"1"
CDS_SEC"1"
MATERIAL"X6S"
TOLERANCE"20%"
VALUE"22UF"
PART_NUMBER"CH622KMEB02"
VOLTAGE"4V"
PACK_TYPE"C0402"
CDS_LIB"pure_quanta";
"B"
$PN"2"20;
"A"
$PN"1"19;
%"Q_CAP"
"1","(-3475,4500)","0","pure_quanta","I102";
;
LOCATION"C2368"
$SEC"1"
CDS_SEC"1"
MATERIAL"X6S"
TOLERANCE"20%"
VALUE"22UF"
PART_NUMBER"CH622KMEB02"
VOLTAGE"4V"
PACK_TYPE"C0402"
CDS_LIB"pure_quanta";
"B"
$PN"2"20;
"A"
$PN"1"19;
%"Q_CAP"
"1","(-3025,4500)","0","pure_quanta","I103";
;
LOCATION"C2374"
$SEC"1"
CDS_SEC"1"
MATERIAL"X6S"
TOLERANCE"20%"
VALUE"22UF"
PART_NUMBER"CH622KMEB02"
VOLTAGE"4V"
PACK_TYPE"C0402"
CDS_LIB"pure_quanta";
"B"
$PN"2"20;
"A"
$PN"1"19;
%"Q_CAP"
"1","(-2575,4500)","0","pure_quanta","I104";
;
LOCATION"C2380"
$SEC"1"
CDS_SEC"1"
MATERIAL"X6S"
TOLERANCE"20%"
VALUE"22UF"
PART_NUMBER"CH622KMEB02"
VOLTAGE"4V"
PACK_TYPE"C0402"
CDS_LIB"pure_quanta";
"B"
$PN"2"20;
"A"
$PN"1"19;
%"Q_CAP"
"1","(-2125,4500)","0","pure_quanta","I105";
;
LOCATION"C2386"
$SEC"1"
CDS_SEC"1"
MATERIAL"X6S"
TOLERANCE"20%"
VALUE"22UF"
PART_NUMBER"CH622KMEB02"
VOLTAGE"4V"
PACK_TYPE"C0402"
CDS_LIB"pure_quanta";
"B"
$PN"2"20;
"A"
$PN"1"19;
%"Q_CAP"
"1","(-1675,4500)","0","pure_quanta","I106";
;
LOCATION"C2392"
$SEC"1"
CDS_SEC"1"
MATERIAL"X6S"
TOLERANCE"20%"
VALUE"22UF"
PART_NUMBER"CH622KMEB02"
VOLTAGE"4V"
PACK_TYPE"C0402"
CDS_LIB"pure_quanta";
"B"
$PN"2"20;
"A"
$PN"1"19;
%"Q_CAP"
"1","(-1225,4500)","0","pure_quanta","I107";
;
LOCATION"C2397"
$SEC"1"
CDS_SEC"1"
MATERIAL"X6S"
TOLERANCE"20%"
VALUE"22UF"
PART_NUMBER"CH622KMEB02"
VOLTAGE"4V"
PACK_TYPE"C0402"
CDS_LIB"pure_quanta";
"B"
$PN"2"20;
"A"
$PN"1"19;
%"UNIVERSAL_GND"
"1","(-825,4125)","0","pure_quanta_power","I108";
;
CDS_LIB"pure_quanta_power"
HDL_POWER"GND";
"A"20;
%"Q_CAP"
"1","(-825,4500)","0","pure_quanta","I109";
;
LOCATION"C2402"
$SEC"1"
CDS_SEC"1"
MATERIAL"X6S"
TOLERANCE"20%"
VALUE"22UF"
PART_NUMBER"CH622KMEB02"
VOLTAGE"4V"
PACK_TYPE"C0402"
CDS_LIB"pure_quanta";
"B"
$PN"2"20;
"A"
$PN"1"19;
%"Q_CAP"
"1","(-8500,2125)","0","pure_quanta","I11";
;
LOCATION"C2309"
$SEC"1"
CDS_SEC"1"
MATERIAL"X6S"
TOLERANCE"20%"
VALUE"22UF"
PART_NUMBER"CH622KMEB02"
VOLTAGE"4V"
PACK_TYPE"C0402"
CDS_LIB"pure_quanta";
"B"
$PN"2"1;
"A"
$PN"1"4;
%"Q_CAP"
"1","(-4825,4500)","0","pure_quanta","I110";
;
LOCATION"C2350"
$SEC"1"
CDS_SEC"1"
MATERIAL"X6S"
TOLERANCE"20%"
VALUE"22UF"
PART_NUMBER"CH622KMEB02"
VOLTAGE"4V"
PACK_TYPE"C0402"
CDS_LIB"pure_quanta";
"B"
$PN"2"20;
"A"
$PN"1"19;
%"Q_CAP"
"1","(-8950,2925)","0","pure_quanta","I12";
;
LOCATION"C2302"
$SEC"1"
CDS_SEC"1"
MATERIAL"X6S"
TOLERANCE"20%"
VALUE"22UF"
PART_NUMBER"CH622KMEB02"
VOLTAGE"4V"
PACK_TYPE"C0402"
CDS_LIB"pure_quanta";
"B"
$PN"2"6;
"A"
$PN"1"5;
%"Q_CAP"
"1","(-8950,3725)","0","pure_quanta","I13";
;
LOCATION"C2301"
$SEC"1"
CDS_SEC"1"
MATERIAL"X6S"
TOLERANCE"20%"
VALUE"22UF"
PART_NUMBER"CH622KMEB02"
VOLTAGE"4V"
PACK_TYPE"C0402"
CDS_LIB"pure_quanta";
"B"
$PN"2"8;
"A"
$PN"1"7;
%"Q_CAP"
"1","(-8500,2925)","0","pure_quanta","I14";
;
LOCATION"C2308"
$SEC"1"
CDS_SEC"1"
MATERIAL"X6S"
TOLERANCE"20%"
VALUE"22UF"
PART_NUMBER"CH622KMEB02"
VOLTAGE"4V"
PACK_TYPE"C0402"
CDS_LIB"pure_quanta";
"B"
$PN"2"6;
"A"
$PN"1"5;
%"Q_CAP"
"1","(-8500,3725)","0","pure_quanta","I15";
;
LOCATION"C2307"
$SEC"1"
CDS_SEC"1"
MATERIAL"X6S"
TOLERANCE"20%"
VALUE"22UF"
PART_NUMBER"CH622KMEB02"
VOLTAGE"4V"
PACK_TYPE"C0402"
CDS_LIB"pure_quanta";
"B"
$PN"2"8;
"A"
$PN"1"7;
%"UNIVERSAL_POWER"
"1","(-9400,4000)","0","pure_quanta_power","I16";
;
HDL_POWER"PVDDCR_CPU0_P1"
CDS_LIB"pure_quanta_power";
"A"7;
%"Q_CAP"
"1","(-9400,4500)","0","pure_quanta","I17";
;
LOCATION"C2294"
$SEC"1"
CDS_SEC"1"
MATERIAL"X6S"
TOLERANCE"20%"
VALUE"22UF"
PART_NUMBER"CH622KMEB02"
VOLTAGE"4V"
PACK_TYPE"C0402"
CDS_LIB"pure_quanta";
"B"
$PN"2"10;
"A"
$PN"1"9;
%"UNIVERSAL_POWER"
"1","(-9400,4775)","0","pure_quanta_power","I18";
;
HDL_POWER"PVDDCR_CPU0_P1"
CDS_LIB"pure_quanta_power";
"A"9;
%"Q_CAP"
"1","(-8950,4500)","0","pure_quanta","I19";
;
LOCATION"C2300"
$SEC"1"
CDS_SEC"1"
MATERIAL"X6S"
TOLERANCE"20%"
VALUE"22UF"
PART_NUMBER"CH622KMEB02"
VOLTAGE"4V"
PACK_TYPE"C0402"
CDS_LIB"pure_quanta";
"B"
$PN"2"10;
"A"
$PN"1"9;
%"UNIVERSAL_POWER"
"1","(-9400,1600)","0","pure_quanta_power","I2";
;
HDL_POWER"PVDDCR_CPU0_P1"
CDS_LIB"pure_quanta_power";
"A"2;
%"Q_CAP"
"1","(-8500,4500)","0","pure_quanta","I20";
;
LOCATION"C2306"
$SEC"1"
CDS_SEC"1"
MATERIAL"X6S"
TOLERANCE"20%"
VALUE"22UF"
PART_NUMBER"CH622KMEB02"
VOLTAGE"4V"
PACK_TYPE"C0402"
CDS_LIB"pure_quanta";
"B"
$PN"2"10;
"A"
$PN"1"9;
%"Q_CAP"
"1","(-8050,1325)","0","pure_quanta","I21";
;
LOCATION"C2316"
$SEC"1"
CDS_SEC"1"
MATERIAL"X6S"
TOLERANCE"20%"
VALUE"22UF"
PART_NUMBER"CH622KMEB02"
VOLTAGE"4V"
PACK_TYPE"C0402"
CDS_LIB"pure_quanta";
"B"
$PN"2"3;
"A"
$PN"1"2;
%"UNIVERSAL_GND"
"1","(-7600,950)","0","pure_quanta_power","I22";
;
CDS_LIB"pure_quanta_power"
HDL_POWER"GND";
"A"3;
%"Q_CAP"
"1","(-7600,1325)","0","pure_quanta","I23";
;
LOCATION"C2322"
$SEC"1"
CDS_SEC"1"
MATERIAL"X6S"
TOLERANCE"20%"
VALUE"22UF"
PART_NUMBER"CH622KMEB02"
VOLTAGE"4V"
PACK_TYPE"C0402"
CDS_LIB"pure_quanta";
"B"
$PN"2"3;
"A"
$PN"1"2;
%"Q_CAP"
"1","(-8050,2125)","0","pure_quanta","I24";
;
LOCATION"C2315"
$SEC"1"
CDS_SEC"1"
MATERIAL"X6S"
TOLERANCE"20%"
VALUE"22UF"
PART_NUMBER"CH622KMEB02"
VOLTAGE"4V"
PACK_TYPE"C0402"
CDS_LIB"pure_quanta";
"B"
$PN"2"1;
"A"
$PN"1"4;
%"Q_CAP"
"1","(-7600,2125)","0","pure_quanta","I25";
;
LOCATION"C2321"
$SEC"1"
CDS_SEC"1"
MATERIAL"X6S"
TOLERANCE"20%"
VALUE"22UF"
PART_NUMBER"CH622KMEB02"
VOLTAGE"4V"
PACK_TYPE"C0402"
CDS_LIB"pure_quanta";
"B"
$PN"2"1;
"A"
$PN"1"4;
%"Q_CAP"
"1","(-7150,2125)","0","pure_quanta","I26";
;
LOCATION"C2327"
$SEC"1"
CDS_SEC"1"
MATERIAL"X6S"
TOLERANCE"20%"
VALUE"22UF"
PART_NUMBER"CH622KMEB02"
VOLTAGE"4V"
PACK_TYPE"C0402"
CDS_LIB"pure_quanta";
"B"
$PN"2"1;
"A"
$PN"1"4;
%"Q_CAP"
"1","(-8050,2925)","0","pure_quanta","I27";
;
LOCATION"C2314"
$SEC"1"
CDS_SEC"1"
MATERIAL"X6S"
TOLERANCE"20%"
VALUE"22UF"
PART_NUMBER"CH622KMEB02"
VOLTAGE"4V"
PACK_TYPE"C0402"
CDS_LIB"pure_quanta";
"B"
$PN"2"6;
"A"
$PN"1"5;
%"Q_CAP"
"1","(-8050,3725)","0","pure_quanta","I28";
;
LOCATION"C2313"
$SEC"1"
CDS_SEC"1"
MATERIAL"X6S"
TOLERANCE"20%"
VALUE"22UF"
PART_NUMBER"CH622KMEB02"
VOLTAGE"4V"
PACK_TYPE"C0402"
CDS_LIB"pure_quanta";
"B"
$PN"2"8;
"A"
$PN"1"7;
%"Q_CAP"
"1","(-7600,2925)","0","pure_quanta","I29";
;
LOCATION"C2320"
$SEC"1"
CDS_SEC"1"
MATERIAL"X6S"
TOLERANCE"20%"
VALUE"22UF"
PART_NUMBER"CH622KMEB02"
VOLTAGE"4V"
PACK_TYPE"C0402"
CDS_LIB"pure_quanta";
"B"
$PN"2"6;
"A"
$PN"1"5;
%"Q_CAP"
"1","(-8950,1325)","0","pure_quanta","I3";
;
LOCATION"C2304"
$SEC"1"
CDS_SEC"1"
MATERIAL"X6S"
TOLERANCE"20%"
VALUE"22UF"
PART_NUMBER"CH622KMEB02"
VOLTAGE"4V"
PACK_TYPE"C0402"
CDS_LIB"pure_quanta";
"B"
$PN"2"3;
"A"
$PN"1"2;
%"Q_CAP"
"1","(-7150,2925)","0","pure_quanta","I30";
;
LOCATION"C2326"
$SEC"1"
CDS_SEC"1"
MATERIAL"X6S"
TOLERANCE"20%"
VALUE"22UF"
PART_NUMBER"CH622KMEB02"
VOLTAGE"4V"
PACK_TYPE"C0402"
CDS_LIB"pure_quanta";
"B"
$PN"2"6;
"A"
$PN"1"5;
%"Q_CAP"
"1","(-7600,3725)","0","pure_quanta","I31";
;
LOCATION"C2319"
$SEC"1"
CDS_SEC"1"
MATERIAL"X6S"
TOLERANCE"20%"
VALUE"22UF"
PART_NUMBER"CH622KMEB02"
VOLTAGE"4V"
PACK_TYPE"C0402"
CDS_LIB"pure_quanta";
"B"
$PN"2"8;
"A"
$PN"1"7;
%"Q_CAP"
"1","(-7150,3725)","0","pure_quanta","I32";
;
LOCATION"C2325"
$SEC"1"
CDS_SEC"1"
MATERIAL"X6S"
TOLERANCE"20%"
VALUE"22UF"
PART_NUMBER"CH622KMEB02"
VOLTAGE"4V"
PACK_TYPE"C0402"
CDS_LIB"pure_quanta";
"B"
$PN"2"8;
"A"
$PN"1"7;
%"Q_CAP"
"1","(-6700,2125)","0","pure_quanta","I33";
;
LOCATION"C2333"
$SEC"1"
CDS_SEC"1"
MATERIAL"X6S"
TOLERANCE"20%"
VALUE"22UF"
PART_NUMBER"CH622KMEB02"
VOLTAGE"4V"
PACK_TYPE"C0402"
CDS_LIB"pure_quanta";
"B"
$PN"2"1;
"A"
$PN"1"4;
%"Q_CAP"
"1","(-6250,2125)","0","pure_quanta","I34";
;
LOCATION"C2338"
$SEC"1"
CDS_SEC"1"
MATERIAL"X6S"
TOLERANCE"20%"
VALUE"22UF"
PART_NUMBER"CH622KMEB02"
VOLTAGE"4V"
PACK_TYPE"C0402"
CDS_LIB"pure_quanta";
"B"
$PN"2"1;
"A"
$PN"1"4;
%"Q_CAP"
"1","(-6700,2925)","0","pure_quanta","I35";
;
LOCATION"C2332"
$SEC"1"
CDS_SEC"1"
MATERIAL"X6S"
TOLERANCE"20%"
VALUE"22UF"
PART_NUMBER"CH622KMEB02"
VOLTAGE"4V"
PACK_TYPE"C0402"
CDS_LIB"pure_quanta";
"B"
$PN"2"6;
"A"
$PN"1"5;
%"Q_CAP"
"1","(-6700,3725)","0","pure_quanta","I36";
;
LOCATION"C2331"
$SEC"1"
CDS_SEC"1"
MATERIAL"X6S"
TOLERANCE"20%"
VALUE"22UF"
PART_NUMBER"CH622KMEB02"
VOLTAGE"4V"
PACK_TYPE"C0402"
CDS_LIB"pure_quanta";
"B"
$PN"2"8;
"A"
$PN"1"7;
%"Q_CAP"
"1","(-6250,2925)","0","pure_quanta","I37";
;
LOCATION"C2337"
$SEC"1"
CDS_SEC"1"
MATERIAL"X6S"
TOLERANCE"20%"
VALUE"22UF"
PART_NUMBER"CH622KMEB02"
VOLTAGE"4V"
PACK_TYPE"C0402"
CDS_LIB"pure_quanta";
"B"
$PN"2"6;
"A"
$PN"1"5;
%"Q_CAP"
"1","(-6250,3725)","0","pure_quanta","I38";
;
LOCATION"C2336"
$SEC"1"
CDS_SEC"1"
MATERIAL"X6S"
TOLERANCE"20%"
VALUE"22UF"
PART_NUMBER"CH622KMEB02"
VOLTAGE"4V"
PACK_TYPE"C0402"
CDS_LIB"pure_quanta";
"B"
$PN"2"8;
"A"
$PN"1"7;
%"UNIVERSAL_POWER"
"1","(-4825,1600)","0","pure_quanta_power","I39";
;
HDL_POWER"PVDDCR_CPU1_P1"
CDS_LIB"pure_quanta_power";
"A"12;
%"Q_CAP"
"1","(-8500,1325)","0","pure_quanta","I4";
;
LOCATION"C2310"
$SEC"1"
CDS_SEC"1"
MATERIAL"X6S"
TOLERANCE"20%"
VALUE"22UF"
PART_NUMBER"CH622KMEB02"
VOLTAGE"4V"
PACK_TYPE"C0402"
CDS_LIB"pure_quanta";
"B"
$PN"2"3;
"A"
$PN"1"2;
%"Q_CAP"
"1","(-4825,1325)","0","pure_quanta","I40";
;
LOCATION"C2354"
$SEC"1"
CDS_SEC"1"
MATERIAL"X6S"
TOLERANCE"20%"
VALUE"22UF"
PART_NUMBER"CH622KMEB02"
VOLTAGE"4V"
PACK_TYPE"C0402"
CDS_LIB"pure_quanta";
"B"
$PN"2"13;
"A"
$PN"1"12;
%"Q_CAP"
"1","(-4375,1325)","0","pure_quanta","I41";
;
LOCATION"C2360"
$SEC"1"
CDS_SEC"1"
MATERIAL"X6S"
TOLERANCE"20%"
VALUE"22UF"
PART_NUMBER"CH622KMEB02"
VOLTAGE"4V"
PACK_TYPE"C0402"
CDS_LIB"pure_quanta";
"B"
$PN"2"13;
"A"
$PN"1"12;
%"Q_CAP"
"1","(-5800,2125)","0","pure_quanta","I42";
;
LOCATION"C2343"
$SEC"1"
CDS_SEC"1"
MATERIAL"X6S"
TOLERANCE"20%"
VALUE"22UF"
PART_NUMBER"CH622KMEB02"
VOLTAGE"4V"
PACK_TYPE"C0402"
CDS_LIB"pure_quanta";
"B"
$PN"2"1;
"A"
$PN"1"4;
%"UNIVERSAL_GND"
"1","(-5400,1750)","0","pure_quanta_power","I43";
;
CDS_LIB"pure_quanta_power"
HDL_POWER"GND";
"A"1;
%"Q_CAP"
"1","(-5400,2125)","0","pure_quanta","I44";
;
LOCATION"C2348"
$SEC"1"
CDS_SEC"1"
MATERIAL"X6S"
TOLERANCE"20%"
VALUE"22UF"
PART_NUMBER"CH622KMEB02"
VOLTAGE"4V"
PACK_TYPE"C0402"
CDS_LIB"pure_quanta";
"B"
$PN"2"1;
"A"
$PN"1"4;
%"UNIVERSAL_GND"
"1","(-5400,2550)","0","pure_quanta_power","I45";
;
CDS_LIB"pure_quanta_power"
HDL_POWER"GND";
"A"6;
%"Q_CAP"
"1","(-5800,2925)","0","pure_quanta","I46";
;
LOCATION"C2342"
$SEC"1"
CDS_SEC"1"
MATERIAL"X6S"
TOLERANCE"20%"
VALUE"22UF"
PART_NUMBER"CH622KMEB02"
VOLTAGE"4V"
PACK_TYPE"C0402"
CDS_LIB"pure_quanta";
"B"
$PN"2"6;
"A"
$PN"1"5;
%"Q_CAP"
"1","(-5800,3725)","0","pure_quanta","I47";
;
LOCATION"C2341"
$SEC"1"
CDS_SEC"1"
MATERIAL"X6S"
TOLERANCE"20%"
VALUE"22UF"
PART_NUMBER"CH622KMEB02"
VOLTAGE"4V"
PACK_TYPE"C0402"
CDS_LIB"pure_quanta";
"B"
$PN"2"8;
"A"
$PN"1"7;
%"Q_CAP"
"1","(-5400,2925)","0","pure_quanta","I48";
;
LOCATION"C2347"
$SEC"1"
CDS_SEC"1"
MATERIAL"X6S"
TOLERANCE"20%"
VALUE"22UF"
PART_NUMBER"CH622KMEB02"
VOLTAGE"4V"
PACK_TYPE"C0402"
CDS_LIB"pure_quanta";
"B"
$PN"2"6;
"A"
$PN"1"5;
%"UNIVERSAL_GND"
"1","(-5400,3350)","0","pure_quanta_power","I49";
;
CDS_LIB"pure_quanta_power"
HDL_POWER"GND";
"A"8;
%"Q_CAP"
"1","(-9400,2125)","0","pure_quanta","I5";
;
LOCATION"C2297"
$SEC"1"
CDS_SEC"1"
MATERIAL"X6S"
TOLERANCE"20%"
VALUE"22UF"
PART_NUMBER"CH622KMEB02"
VOLTAGE"4V"
PACK_TYPE"C0402"
CDS_LIB"pure_quanta";
"B"
$PN"2"1;
"A"
$PN"1"4;
%"Q_CAP"
"1","(-5400,3725)","0","pure_quanta","I50";
;
LOCATION"C2346"
$SEC"1"
CDS_SEC"1"
MATERIAL"X6S"
TOLERANCE"20%"
VALUE"22UF"
PART_NUMBER"CH622KMEB02"
VOLTAGE"4V"
PACK_TYPE"C0402"
CDS_LIB"pure_quanta";
"B"
$PN"2"8;
"A"
$PN"1"7;
%"Q_CAP"
"1","(-4825,2125)","0","pure_quanta","I51";
;
LOCATION"C2353"
$SEC"1"
CDS_SEC"1"
MATERIAL"X6S"
TOLERANCE"20%"
VALUE"22UF"
PART_NUMBER"CH622KMEB02"
VOLTAGE"4V"
PACK_TYPE"C0402"
CDS_LIB"pure_quanta";
"B"
$PN"2"11;
"A"
$PN"1"15;
%"UNIVERSAL_POWER"
"1","(-4825,2400)","0","pure_quanta_power","I52";
;
HDL_POWER"PVDDCR_CPU1_P1"
CDS_LIB"pure_quanta_power";
"A"15;
%"Q_CAP"
"1","(-4375,2125)","0","pure_quanta","I53";
;
LOCATION"C2359"
$SEC"1"
CDS_SEC"1"
MATERIAL"X6S"
TOLERANCE"20%"
VALUE"22UF"
PART_NUMBER"CH622KMEB02"
VOLTAGE"4V"
PACK_TYPE"C0402"
CDS_LIB"pure_quanta";
"B"
$PN"2"11;
"A"
$PN"1"15;
%"UNIVERSAL_POWER"
"1","(-4825,3200)","0","pure_quanta_power","I54";
;
HDL_POWER"PVDDCR_CPU1_P1"
CDS_LIB"pure_quanta_power";
"A"18;
%"Q_CAP"
"1","(-4825,2925)","0","pure_quanta","I55";
;
LOCATION"C2352"
$SEC"1"
CDS_SEC"1"
MATERIAL"X6S"
TOLERANCE"20%"
VALUE"22UF"
PART_NUMBER"CH622KMEB02"
VOLTAGE"4V"
PACK_TYPE"C0402"
CDS_LIB"pure_quanta";
"B"
$PN"2"14;
"A"
$PN"1"18;
%"Q_CAP"
"1","(-4825,3725)","0","pure_quanta","I56";
;
LOCATION"C2351"
$SEC"1"
CDS_SEC"1"
MATERIAL"X6S"
TOLERANCE"20%"
VALUE"22UF"
PART_NUMBER"CH622KMEB02"
VOLTAGE"4V"
PACK_TYPE"C0402"
CDS_LIB"pure_quanta";
"B"
$PN"2"17;
"A"
$PN"1"16;
%"Q_CAP"
"1","(-4375,2925)","0","pure_quanta","I57";
;
LOCATION"C2358"
$SEC"1"
CDS_SEC"1"
MATERIAL"X6S"
TOLERANCE"20%"
VALUE"22UF"
PART_NUMBER"CH622KMEB02"
VOLTAGE"4V"
PACK_TYPE"C0402"
CDS_LIB"pure_quanta";
"B"
$PN"2"14;
"A"
$PN"1"18;
%"Q_CAP"
"1","(-4375,3725)","0","pure_quanta","I58";
;
LOCATION"C2357"
$SEC"1"
CDS_SEC"1"
MATERIAL"X6S"
TOLERANCE"20%"
VALUE"22UF"
PART_NUMBER"CH622KMEB02"
VOLTAGE"4V"
PACK_TYPE"C0402"
CDS_LIB"pure_quanta";
"B"
$PN"2"17;
"A"
$PN"1"16;
%"Q_CAP"
"1","(-8050,4500)","0","pure_quanta","I59";
;
LOCATION"C2312"
$SEC"1"
CDS_SEC"1"
MATERIAL"X6S"
TOLERANCE"20%"
VALUE"22UF"
PART_NUMBER"CH622KMEB02"
VOLTAGE"4V"
PACK_TYPE"C0402"
CDS_LIB"pure_quanta";
"B"
$PN"2"10;
"A"
$PN"1"9;
%"UNIVERSAL_POWER"
"1","(-9400,2400)","0","pure_quanta_power","I6";
;
HDL_POWER"PVDDCR_CPU0_P1"
CDS_LIB"pure_quanta_power";
"A"4;
%"Q_CAP"
"1","(-7600,4500)","0","pure_quanta","I60";
;
LOCATION"C2318"
$SEC"1"
CDS_SEC"1"
MATERIAL"X6S"
TOLERANCE"20%"
VALUE"22UF"
PART_NUMBER"CH622KMEB02"
VOLTAGE"4V"
PACK_TYPE"C0402"
CDS_LIB"pure_quanta";
"B"
$PN"2"10;
"A"
$PN"1"9;
%"Q_CAP"
"1","(-7150,4500)","0","pure_quanta","I61";
;
LOCATION"C2324"
$SEC"1"
CDS_SEC"1"
MATERIAL"X6S"
TOLERANCE"20%"
VALUE"22UF"
PART_NUMBER"CH622KMEB02"
VOLTAGE"4V"
PACK_TYPE"C0402"
CDS_LIB"pure_quanta";
"B"
$PN"2"10;
"A"
$PN"1"9;
%"Q_CAP"
"1","(-6700,4500)","0","pure_quanta","I62";
;
LOCATION"C2330"
$SEC"1"
CDS_SEC"1"
MATERIAL"X6S"
TOLERANCE"20%"
VALUE"22UF"
PART_NUMBER"CH622KMEB02"
VOLTAGE"4V"
PACK_TYPE"C0402"
CDS_LIB"pure_quanta";
"B"
$PN"2"10;
"A"
$PN"1"9;
%"Q_CAP"
"1","(-6250,4500)","0","pure_quanta","I63";
;
LOCATION"C2335"
$SEC"1"
CDS_SEC"1"
MATERIAL"X6S"
TOLERANCE"20%"
VALUE"22UF"
PART_NUMBER"CH622KMEB02"
VOLTAGE"4V"
PACK_TYPE"C0402"
CDS_LIB"pure_quanta";
"B"
$PN"2"10;
"A"
$PN"1"9;
%"Q_CAP"
"1","(-5800,4500)","0","pure_quanta","I64";
;
LOCATION"C2340"
$SEC"1"
CDS_SEC"1"
MATERIAL"X6S"
TOLERANCE"20%"
VALUE"22UF"
PART_NUMBER"CH622KMEB02"
VOLTAGE"4V"
PACK_TYPE"C0402"
CDS_LIB"pure_quanta";
"B"
$PN"2"10;
"A"
$PN"1"9;
%"UNIVERSAL_GND"
"1","(-5400,4125)","0","pure_quanta_power","I65";
;
CDS_LIB"pure_quanta_power"
HDL_POWER"GND";
"A"10;
%"Q_CAP"
"1","(-5400,4500)","0","pure_quanta","I66";
;
LOCATION"C2345"
$SEC"1"
CDS_SEC"1"
MATERIAL"X6S"
TOLERANCE"20%"
VALUE"22UF"
PART_NUMBER"CH622KMEB02"
VOLTAGE"4V"
PACK_TYPE"C0402"
CDS_LIB"pure_quanta";
"B"
$PN"2"10;
"A"
$PN"1"9;
%"UNIVERSAL_POWER"
"1","(-4825,4000)","0","pure_quanta_power","I67";
;
HDL_POWER"PVDDCR_CPU1_P1"
CDS_LIB"pure_quanta_power";
"A"16;
%"Q_CAP"
"1","(-4375,4500)","0","pure_quanta","I68";
;
LOCATION"C2356"
$SEC"1"
CDS_SEC"1"
MATERIAL"X6S"
TOLERANCE"20%"
VALUE"22UF"
PART_NUMBER"CH622KMEB02"
VOLTAGE"4V"
PACK_TYPE"C0402"
CDS_LIB"pure_quanta";
"B"
$PN"2"20;
"A"
$PN"1"19;
%"UNIVERSAL_POWER"
"1","(-4825,4775)","0","pure_quanta_power","I69";
;
HDL_POWER"PVDDCR_CPU1_P1"
CDS_LIB"pure_quanta_power";
"A"19;
%"Q_CAP"
"1","(-9400,2925)","0","pure_quanta","I7";
;
LOCATION"C2296"
$SEC"1"
CDS_SEC"1"
MATERIAL"X6S"
TOLERANCE"20%"
VALUE"22UF"
PART_NUMBER"CH622KMEB02"
VOLTAGE"4V"
PACK_TYPE"C0402"
CDS_LIB"pure_quanta";
"B"
$PN"2"6;
"A"
$PN"1"5;
%"Q_CAP"
"1","(-3925,1325)","0","pure_quanta","I70";
;
LOCATION"C2366"
$SEC"1"
CDS_SEC"1"
MATERIAL"X6S"
TOLERANCE"20%"
VALUE"22UF"
PART_NUMBER"CH622KMEB02"
VOLTAGE"4V"
PACK_TYPE"C0402"
CDS_LIB"pure_quanta";
"B"
$PN"2"13;
"A"
$PN"1"12;
%"Q_CAP"
"1","(-3475,1325)","0","pure_quanta","I71";
;
LOCATION"C2372"
$SEC"1"
CDS_SEC"1"
MATERIAL"X6S"
TOLERANCE"20%"
VALUE"22UF"
PART_NUMBER"CH622KMEB02"
VOLTAGE"4V"
PACK_TYPE"C0402"
CDS_LIB"pure_quanta";
"B"
$PN"2"13;
"A"
$PN"1"12;
%"Q_CAP"
"1","(-3025,1325)","0","pure_quanta","I72";
;
LOCATION"C2378"
$SEC"1"
CDS_SEC"1"
MATERIAL"X6S"
TOLERANCE"20%"
VALUE"22UF"
PART_NUMBER"CH622KMEB02"
VOLTAGE"4V"
PACK_TYPE"C0402"
CDS_LIB"pure_quanta";
"B"
$PN"2"13;
"A"
$PN"1"12;
%"UNIVERSAL_GND"
"1","(-3025,950)","0","pure_quanta_power","I73";
;
CDS_LIB"pure_quanta_power"
HDL_POWER"GND";
"A"13;
%"Q_CAP"
"1","(-3925,2125)","0","pure_quanta","I74";
;
LOCATION"C2365"
$SEC"1"
CDS_SEC"1"
MATERIAL"X6S"
TOLERANCE"20%"
VALUE"22UF"
PART_NUMBER"CH622KMEB02"
VOLTAGE"4V"
PACK_TYPE"C0402"
CDS_LIB"pure_quanta";
"B"
$PN"2"11;
"A"
$PN"1"15;
%"Q_CAP"
"1","(-3475,2125)","0","pure_quanta","I75";
;
LOCATION"C2371"
$SEC"1"
CDS_SEC"1"
MATERIAL"X6S"
TOLERANCE"20%"
VALUE"22UF"
PART_NUMBER"CH622KMEB02"
VOLTAGE"4V"
PACK_TYPE"C0402"
CDS_LIB"pure_quanta";
"B"
$PN"2"11;
"A"
$PN"1"15;
%"Q_CAP"
"1","(-3925,2925)","0","pure_quanta","I76";
;
LOCATION"C2364"
$SEC"1"
CDS_SEC"1"
MATERIAL"X6S"
TOLERANCE"20%"
VALUE"22UF"
PART_NUMBER"CH622KMEB02"
VOLTAGE"4V"
PACK_TYPE"C0402"
CDS_LIB"pure_quanta";
"B"
$PN"2"14;
"A"
$PN"1"18;
%"Q_CAP"
"1","(-3925,3725)","0","pure_quanta","I77";
;
LOCATION"C2363"
$SEC"1"
CDS_SEC"1"
MATERIAL"X6S"
TOLERANCE"20%"
VALUE"22UF"
PART_NUMBER"CH622KMEB02"
VOLTAGE"4V"
PACK_TYPE"C0402"
CDS_LIB"pure_quanta";
"B"
$PN"2"17;
"A"
$PN"1"16;
%"Q_CAP"
"1","(-3475,2925)","0","pure_quanta","I78";
;
LOCATION"C2370"
$SEC"1"
CDS_SEC"1"
MATERIAL"X6S"
TOLERANCE"20%"
VALUE"22UF"
PART_NUMBER"CH622KMEB02"
VOLTAGE"4V"
PACK_TYPE"C0402"
CDS_LIB"pure_quanta";
"B"
$PN"2"14;
"A"
$PN"1"18;
%"Q_CAP"
"1","(-3475,3725)","0","pure_quanta","I79";
;
LOCATION"C2369"
$SEC"1"
CDS_SEC"1"
MATERIAL"X6S"
TOLERANCE"20%"
VALUE"22UF"
PART_NUMBER"CH622KMEB02"
VOLTAGE"4V"
PACK_TYPE"C0402"
CDS_LIB"pure_quanta";
"B"
$PN"2"17;
"A"
$PN"1"16;
%"UNIVERSAL_POWER"
"1","(-9400,3200)","0","pure_quanta_power","I8";
;
HDL_POWER"PVDDCR_CPU0_P1"
CDS_LIB"pure_quanta_power";
"A"5;
%"Q_CAP"
"1","(-3025,2925)","0","pure_quanta","I80";
;
LOCATION"C2376"
$SEC"1"
CDS_SEC"1"
MATERIAL"X6S"
TOLERANCE"20%"
VALUE"22UF"
PART_NUMBER"CH622KMEB02"
VOLTAGE"4V"
PACK_TYPE"C0402"
CDS_LIB"pure_quanta";
"B"
$PN"2"14;
"A"
$PN"1"18;
%"Q_CAP"
"1","(-3025,2125)","0","pure_quanta","I81";
;
LOCATION"C2377"
$SEC"1"
CDS_SEC"1"
MATERIAL"X6S"
TOLERANCE"20%"
VALUE"22UF"
PART_NUMBER"CH622KMEB02"
VOLTAGE"4V"
PACK_TYPE"C0402"
CDS_LIB"pure_quanta";
"B"
$PN"2"11;
"A"
$PN"1"15;
%"Q_CAP"
"1","(-2575,2125)","0","pure_quanta","I82";
;
LOCATION"C2383"
$SEC"1"
CDS_SEC"1"
MATERIAL"X6S"
TOLERANCE"20%"
VALUE"22UF"
PART_NUMBER"CH622KMEB02"
VOLTAGE"4V"
PACK_TYPE"C0402"
CDS_LIB"pure_quanta";
"B"
$PN"2"11;
"A"
$PN"1"15;
%"Q_CAP"
"1","(-2125,2125)","0","pure_quanta","I83";
;
LOCATION"C2389"
$SEC"1"
CDS_SEC"1"
MATERIAL"X6S"
TOLERANCE"20%"
VALUE"22UF"
PART_NUMBER"CH622KMEB02"
VOLTAGE"4V"
PACK_TYPE"C0402"
CDS_LIB"pure_quanta";
"B"
$PN"2"11;
"A"
$PN"1"15;
%"Q_CAP"
"1","(-2575,2925)","0","pure_quanta","I84";
;
LOCATION"C2382"
$SEC"1"
CDS_SEC"1"
MATERIAL"X6S"
TOLERANCE"20%"
VALUE"22UF"
PART_NUMBER"CH622KMEB02"
VOLTAGE"4V"
PACK_TYPE"C0402"
CDS_LIB"pure_quanta";
"B"
$PN"2"14;
"A"
$PN"1"18;
%"Q_CAP"
"1","(-3025,3725)","0","pure_quanta","I85";
;
LOCATION"C2375"
$SEC"1"
CDS_SEC"1"
MATERIAL"X6S"
TOLERANCE"20%"
VALUE"22UF"
PART_NUMBER"CH622KMEB02"
VOLTAGE"4V"
PACK_TYPE"C0402"
CDS_LIB"pure_quanta";
"B"
$PN"2"17;
"A"
$PN"1"16;
%"Q_CAP"
"1","(-2575,3725)","0","pure_quanta","I86";
;
LOCATION"C2381"
$SEC"1"
CDS_SEC"1"
MATERIAL"X6S"
TOLERANCE"20%"
VALUE"22UF"
PART_NUMBER"CH622KMEB02"
VOLTAGE"4V"
PACK_TYPE"C0402"
CDS_LIB"pure_quanta";
"B"
$PN"2"17;
"A"
$PN"1"16;
%"Q_CAP"
"1","(-2125,2925)","0","pure_quanta","I87";
;
LOCATION"C2388"
$SEC"1"
CDS_SEC"1"
MATERIAL"X6S"
TOLERANCE"20%"
VALUE"22UF"
PART_NUMBER"CH622KMEB02"
VOLTAGE"4V"
PACK_TYPE"C0402"
CDS_LIB"pure_quanta";
"B"
$PN"2"14;
"A"
$PN"1"18;
%"Q_CAP"
"1","(-2125,3725)","0","pure_quanta","I88";
;
LOCATION"C2387"
$SEC"1"
CDS_SEC"1"
MATERIAL"X6S"
TOLERANCE"20%"
VALUE"22UF"
PART_NUMBER"CH622KMEB02"
VOLTAGE"4V"
PACK_TYPE"C0402"
CDS_LIB"pure_quanta";
"B"
$PN"2"17;
"A"
$PN"1"16;
%"Q_CAP"
"1","(-1675,2125)","0","pure_quanta","I89";
;
LOCATION"C2395"
$SEC"1"
CDS_SEC"1"
MATERIAL"X6S"
TOLERANCE"20%"
VALUE"22UF"
PART_NUMBER"CH622KMEB02"
VOLTAGE"4V"
PACK_TYPE"C0402"
CDS_LIB"pure_quanta";
"B"
$PN"2"11;
"A"
$PN"1"15;
%"Q_CAP"
"1","(-9400,3725)","0","pure_quanta","I9";
;
LOCATION"C2295"
$SEC"1"
CDS_SEC"1"
MATERIAL"X6S"
TOLERANCE"20%"
VALUE"22UF"
PART_NUMBER"CH622KMEB02"
VOLTAGE"4V"
PACK_TYPE"C0402"
CDS_LIB"pure_quanta";
"B"
$PN"2"8;
"A"
$PN"1"7;
%"Q_CAP"
"1","(-1225,2125)","0","pure_quanta","I90";
;
LOCATION"C2400"
$SEC"1"
CDS_SEC"1"
MATERIAL"X6S"
TOLERANCE"20%"
VALUE"22UF"
PART_NUMBER"CH622KMEB02"
VOLTAGE"4V"
PACK_TYPE"C0402"
CDS_LIB"pure_quanta";
"B"
$PN"2"11;
"A"
$PN"1"15;
%"Q_CAP"
"1","(-1675,2925)","0","pure_quanta","I91";
;
LOCATION"C2394"
$SEC"1"
CDS_SEC"1"
MATERIAL"X6S"
TOLERANCE"20%"
VALUE"22UF"
PART_NUMBER"CH622KMEB02"
VOLTAGE"4V"
PACK_TYPE"C0402"
CDS_LIB"pure_quanta";
"B"
$PN"2"14;
"A"
$PN"1"18;
%"Q_CAP"
"1","(-1675,3725)","0","pure_quanta","I92";
;
LOCATION"C2393"
$SEC"1"
CDS_SEC"1"
MATERIAL"X6S"
TOLERANCE"20%"
VALUE"22UF"
PART_NUMBER"CH622KMEB02"
VOLTAGE"4V"
PACK_TYPE"C0402"
CDS_LIB"pure_quanta";
"B"
$PN"2"17;
"A"
$PN"1"16;
%"Q_CAP"
"1","(-1225,2925)","0","pure_quanta","I93";
;
LOCATION"C2399"
$SEC"1"
CDS_SEC"1"
MATERIAL"X6S"
TOLERANCE"20%"
VALUE"22UF"
PART_NUMBER"CH622KMEB02"
VOLTAGE"4V"
PACK_TYPE"C0402"
CDS_LIB"pure_quanta";
"B"
$PN"2"14;
"A"
$PN"1"18;
%"Q_CAP"
"1","(-1225,3725)","0","pure_quanta","I94";
;
LOCATION"C2398"
$SEC"1"
CDS_SEC"1"
MATERIAL"X6S"
TOLERANCE"20%"
VALUE"22UF"
PART_NUMBER"CH622KMEB02"
VOLTAGE"4V"
PACK_TYPE"C0402"
CDS_LIB"pure_quanta";
"B"
$PN"2"17;
"A"
$PN"1"16;
%"UNIVERSAL_GND"
"1","(-825,1750)","0","pure_quanta_power","I95";
;
CDS_LIB"pure_quanta_power"
HDL_POWER"GND";
"A"11;
%"Q_CAP"
"1","(-825,2125)","0","pure_quanta","I96";
;
LOCATION"C2405"
$SEC"1"
CDS_SEC"1"
MATERIAL"X6S"
TOLERANCE"20%"
VALUE"22UF"
PART_NUMBER"CH622KMEB02"
VOLTAGE"4V"
PACK_TYPE"C0402"
CDS_LIB"pure_quanta";
"B"
$PN"2"11;
"A"
$PN"1"15;
%"UNIVERSAL_GND"
"1","(-825,2550)","0","pure_quanta_power","I97";
;
CDS_LIB"pure_quanta_power"
HDL_POWER"GND";
"A"14;
%"Q_CAP"
"1","(-825,2925)","0","pure_quanta","I98";
;
LOCATION"C2404"
$SEC"1"
CDS_SEC"1"
MATERIAL"X6S"
TOLERANCE"20%"
VALUE"22UF"
PART_NUMBER"CH622KMEB02"
VOLTAGE"4V"
PACK_TYPE"C0402"
CDS_LIB"pure_quanta";
"B"
$PN"2"14;
"A"
$PN"1"18;
%"UNIVERSAL_GND"
"1","(-825,3350)","0","pure_quanta_power","I99";
;
CDS_LIB"pure_quanta_power"
HDL_POWER"GND";
"A"17;
END.
